(kicad_pcb
	(version 20260206)
	(generator "pcbnew")
	(generator_version "10.0")
	(general
		(thickness 1.6)
		(legacy_teardrops no)
	)
	(paper "A4")
	(title_block
		(title "dpb — 14545-sa.0730WZS0815.brd")
		(comment 1 "Honey Badger (Wiwynn) / footprints 315-319 of 1066")
	)
	(layers
		(0 "F.Cu" signal "TOP")
		(4 "In1.Cu" signal "L2GND")
		(6 "In2.Cu" signal "L3")
		(8 "In3.Cu" signal "L4VCC")
		(10 "In4.Cu" signal "L5VCC")
		(12 "In5.Cu" signal "L6")
		(14 "In6.Cu" signal "L7GND")
		(2 "B.Cu" signal "BOTTOM")
		(9 "F.Adhes" user "F.Adhesive")
		(11 "B.Adhes" user "B.Adhesive")
		(13 "F.Paste" user "Package Geometry/Pastemask Top")
		(15 "B.Paste" user "Package Geometry/Pastemask Bottom")
		(5 "F.SilkS" user "Ref Des/Silkscreen Top")
		(7 "B.SilkS" user "Ref Des/Silkscreen Bottom")
		(1 "F.Mask" user "Board Geometry/Soldermask Top")
		(3 "B.Mask" user "Board Geometry/Soldermask Bottom")
		(17 "Dwgs.User" user "User.Drawings")
		(19 "Cmts.User" user "User.Comments")
		(21 "Eco1.User" user "User.Eco1")
		(23 "Eco2.User" user "User.Eco2")
		(25 "Edge.Cuts" user "Board Geometry/Outline")
		(27 "Margin" user)
		(31 "F.CrtYd" user "Package Geometry/Place Bound Top")
		(29 "B.CrtYd" user "Package Geometry/Place Bound Bottom")
		(35 "F.Fab" user "Ref Des/Assembly Top")
		(33 "B.Fab" user "Ref Des/Assembly Bottom")
	)
	(footprint ""
		(layer "F.Cu")
		(at 235.838746 -21.7297 90)
		(property "Reference" "PU1"
			(at 0 0 90)
			(layer "F.SilkS")
			(hide yes)
			(effects
				(font
					(size 1.27 1.27)
				)
			)
		)
		(property "Value" "TPS53319DQPR-GP"
			(at 4.7498 -5.6896 90)
			(unlocked yes)
			(layer "F.Fab")
			(hide yes)
			(effects
				(font
					(size 1.016 1.016)
					(thickness 0.1524)
				)
			)
		)
		(property "Device Type" "QFN22G6050-G6133H60"
			(at 4.7498 -7.2136 90)
			(unlocked yes)
			(layer "F.Fab")
			(hide yes)
			(effects
				(font
					(size 1.016 1.016)
					(thickness 0.1524)
				)
			)
		)
		(duplicate_pad_numbers_are_jumpers no)
		(fp_line
			(start -2.286 -3.5179)
			(end -3.556 -3.5179)
			(stroke
				(width 0.1524)
				(type default)
			)
			(layer "F.SilkS")
		)
		(fp_line
			(start -3.556 -3.5179)
			(end -3.556 -2.2479)
			(stroke
				(width 0.1524)
				(type default)
			)
			(layer "F.SilkS")
		)
		(fp_line
			(start 0.500126 -3.262122)
			(end 0.500126 -3.770122)
			(stroke
				(width 0.1524)
				(type default)
			)
			(layer "F.SilkS")
		)
		(fp_line
			(start -1.999996 -3.262122)
			(end -1.999996 -4.024122)
			(stroke
				(width 0.1524)
				(type default)
			)
			(layer "F.SilkS")
		)
		(fp_line
			(start -3.556 2.2479)
			(end -3.556 3.5179)
			(stroke
				(width 0.1524)
				(type default)
			)
			(layer "F.SilkS")
		)
		(fp_line
			(start 1.500124 3.262122)
			(end 1.500124 4.024122)
			(stroke
				(width 0.1524)
				(type default)
			)
			(layer "F.SilkS")
		)
		(fp_line
			(start -0.999998 3.262122)
			(end -0.999998 3.770122)
			(stroke
				(width 0.1524)
				(type default)
			)
			(layer "F.SilkS")
		)
		(fp_line
			(start 3.556 3.5179)
			(end 3.556 2.2479)
			(stroke
				(width 0.1524)
				(type default)
			)
			(layer "F.SilkS")
		)
		(fp_line
			(start 2.286 3.5179)
			(end 3.556 3.5179)
			(stroke
				(width 0.1524)
				(type default)
			)
			(layer "F.SilkS")
		)
		(fp_line
			(start -3.556 3.5179)
			(end -2.286 3.5179)
			(stroke
				(width 0.1524)
				(type default)
			)
			(layer "F.SilkS")
		)
		(fp_poly
			(pts
				(xy 3.556 -3.5179) (xy 2.5273 -3.5179) (xy 3.556 -2.4892)
			)
			(stroke
				(width 0)
				(type default)
			)
			(fill yes)
			(layer "F.SilkS")
		)
		(fp_rect
			(start -2.9972 2.5019)
			(end 2.9972 -2.5019)
			(stroke
				(width 0)
				(type default)
			)
			(fill no)
			(layer "F.CrtYd")
		)
		(fp_poly
			(pts
				(xy 3.556 -2.5019) (xy -2.9972 -2.5019) (xy -2.9972 2.5019) (xy 2.9972 2.5019) (xy 2.9972 -2.4892)
				(xy 3.556 -2.4892) (xy 3.556 3.5179) (xy -3.556 3.5179) (xy -3.556 -3.5179) (xy 3.556 -3.5179)
			)
			(stroke
				(width 0)
				(type default)
			)
			(fill no)
			(layer "F.CrtYd")
		)
		(fp_rect
			(start -3.556 3.5179)
			(end 3.556 -3.5179)
			(stroke
				(width 0)
				(type default)
			)
			(fill no)
			(layer "F.Fab")
		)
		(pad "1" smd rect
			(at 2.500122 -2.449322 90)
			(size 0.3048 1.1176)
			(layers "F.Cu" "F.Mask" "F.Paste")
			(net "P5VA_VFB")
		)
		(pad "2" smd rect
			(at 1.999996 -2.449322 90)
			(size 0.3048 1.1176)
			(layers "F.Cu" "F.Mask" "F.Paste")
			(net "P5VA_EN")
		)
		(pad "3" smd rect
			(at 1.500124 -2.449322 90)
			(size 0.3048 1.1176)
			(layers "F.Cu" "F.Mask" "F.Paste")
			(net "P5VA_PGD")
		)
		(pad "4" smd rect
			(at 0.999998 -2.449322 90)
			(size 0.3048 1.1176)
			(layers "F.Cu" "F.Mask" "F.Paste")
			(net "P5VA_VBST")
		)
		(pad "5" smd rect
			(at 0.500126 -2.449322 90)
			(size 0.3048 1.1176)
			(layers "F.Cu" "F.Mask" "F.Paste")
			(net "P5VA_ROVP")
		)
		(pad "6" smd rect
			(at 0 -2.449322 90)
			(size 0.3048 1.1176)
			(layers "F.Cu" "F.Mask" "F.Paste")
			(net "P5VA_LL")
		)
		(pad "7" smd rect
			(at -0.500126 -2.449322 90)
			(size 0.3048 1.1176)
			(layers "F.Cu" "F.Mask" "F.Paste")
			(net "P5VA_LL")
		)
		(pad "8" smd rect
			(at -0.999998 -2.449322 90)
			(size 0.3048 1.1176)
			(layers "F.Cu" "F.Mask" "F.Paste")
			(net "P5VA_LL")
		)
		(pad "9" smd rect
			(at -1.500124 -2.449322 90)
			(size 0.3048 1.1176)
			(layers "F.Cu" "F.Mask" "F.Paste")
			(net "P5VA_LL")
		)
		(pad "10" smd rect
			(at -1.999996 -2.449322 90)
			(size 0.3048 1.1176)
			(layers "F.Cu" "F.Mask" "F.Paste")
			(net "P5VA_LL")
		)
		(pad "11" smd rect
			(at -2.500122 -2.449322 90)
			(size 0.3048 1.1176)
			(layers "F.Cu" "F.Mask" "F.Paste")
			(net "P5VA_LL")
		)
		(pad "12" smd rect
			(at -2.500122 2.449322 90)
			(size 0.3048 1.1176)
			(layers "F.Cu" "F.Mask" "F.Paste")
			(net "P5VA_12VIN")
		)
		(pad "13" smd rect
			(at -1.999996 2.449322 90)
			(size 0.3048 1.1176)
			(layers "F.Cu" "F.Mask" "F.Paste")
			(net "P5VA_12VIN")
		)
		(pad "14" smd rect
			(at -1.500124 2.449322 90)
			(size 0.3048 1.1176)
			(layers "F.Cu" "F.Mask" "F.Paste")
			(net "P5VA_12VIN")
		)
		(pad "15" smd rect
			(at -0.999998 2.449322 90)
			(size 0.3048 1.1176)
			(layers "F.Cu" "F.Mask" "F.Paste")
			(net "P5VA_12VIN")
		)
		(pad "16" smd rect
			(at -0.500126 2.449322 90)
			(size 0.3048 1.1176)
			(layers "F.Cu" "F.Mask" "F.Paste")
			(net "P5VA_12VIN")
		)
		(pad "17" smd rect
			(at 0 2.449322 90)
			(size 0.3048 1.1176)
			(layers "F.Cu" "F.Mask" "F.Paste")
			(net "P5VA_12VIN")
		)
		(pad "18" smd rect
			(at 0.500126 2.449322 90)
			(size 0.3048 1.1176)
			(layers "F.Cu" "F.Mask" "F.Paste")
			(net "P5VA_VREG")
		)
		(pad "19" smd rect
			(at 0.999998 2.449322 90)
			(size 0.3048 1.1176)
			(layers "F.Cu" "F.Mask" "F.Paste")
			(net "P5VA_VDD")
		)
		(pad "20" smd rect
			(at 1.500124 2.449322 90)
			(size 0.3048 1.1176)
			(layers "F.Cu" "F.Mask" "F.Paste")
			(net "P5VA_MODE")
		)
		(pad "21" smd rect
			(at 1.999996 2.449322 90)
			(size 0.3048 1.1176)
			(layers "F.Cu" "F.Mask" "F.Paste")
			(net "P5VA_TRIP")
		)
		(pad "22" smd rect
			(at 2.500122 2.449322 90)
			(size 0.3048 1.1176)
			(layers "F.Cu" "F.Mask" "F.Paste")
			(net "P5VA_RF")
		)
		(pad "23" smd custom
			(at 0 0 90)
			(size 0.83185 0.83185)
			(layers "F.Cu" "F.Mask" "F.Paste")
			(net "GND")
			(options
				(clearance outline)
				(anchor circle)
			)
			(primitives
				(gr_poly
					(pts
						(xy -2.7813 1.6637) (xy -2.7813 1.2954) (xy -3.048 1.2954) (xy -3.048 0.9525) (xy -2.7813 0.9525)
						(xy -2.7813 -0.9525) (xy -3.048 -0.9525) (xy -3.048 -1.2954) (xy -2.7813 -1.2954) (xy -2.7813 -1.6637)
						(xy 2.7813 -1.6637) (xy 2.7813 -1.2954) (xy 3.048 -1.2954) (xy 3.048 -0.9525) (xy 2.7813 -0.9525)
						(xy 2.7813 0.9525) (xy 3.048 0.9525) (xy 3.048 1.2954) (xy 2.7813 1.2954) (xy 2.7813 1.6637)
					)
					(width 0)
					(fill yes)
				)
			)
		)
	)
	(footprint ""
		(layer "F.Cu")
		(at 26.55443 -242.059206 90)
		(property "Reference" "C295"
			(at 0 0 90)
			(layer "F.SilkS")
			(hide yes)
			(effects
				(font
					(size 1.27 1.27)
				)
			)
		)
		(property "Value" "SCD01U50V2KX-1GP"
			(at 1.1811 -2.7051 90)
			(unlocked yes)
			(layer "F.Fab")
			(hide yes)
			(effects
				(font
					(size 1.016 1.016)
					(thickness 0.1524)
				)
			)
		)
		(property "Device Type" "C402H22"
			(at 1.1811 -4.2291 90)
			(unlocked yes)
			(layer "F.Fab")
			(hide yes)
			(effects
				(font
					(size 1.016 1.016)
					(thickness 0.1524)
				)
			)
		)
		(duplicate_pad_numbers_are_jumpers no)
		(fp_rect
			(start -0.4318 0.9525)
			(end 0.4318 -0.9525)
			(stroke
				(width 0)
				(type default)
			)
			(fill no)
			(layer "F.CrtYd")
		)
		(fp_rect
			(start -0.4318 0.9525)
			(end 0.4318 -0.9525)
			(stroke
				(width 0)
				(type default)
			)
			(fill no)
			(layer "F.Fab")
		)
		(pad "1" smd custom
			(at 0 -0.4445 90)
			(size 0.1524 0.1524)
			(layers "F.Cu" "F.Mask" "F.Paste")
			(net "SAS2X28_DRIVE_RX_P_A12")
			(options
				(clearance outline)
				(anchor circle)
			)
			(primitives
				(gr_poly
					(pts
						(arc
							(start 0.3048 -0.2032)
							(mid 0.275042 -0.275042)
							(end 0.2032 -0.3048)
						)
						(arc
							(start -0.2032 -0.3048)
							(mid -0.275042 -0.275042)
							(end -0.3048 -0.2032)
						)
						(arc
							(start -0.3048 0.2032)
							(mid -0.275042 0.275042)
							(end -0.2032 0.3048)
						)
						(arc
							(start 0.2032 0.3048)
							(mid 0.275042 0.275042)
							(end 0.3048 0.2032)
						)
					)
					(width 0)
					(fill yes)
				)
			)
		)
		(pad "2" smd custom
			(at 0 0.4445 90)
			(size 0.1524 0.1524)
			(layers "F.Cu" "F.Mask" "F.Paste")
			(net "SAS2X28_A_HDD12_RX_+")
			(options
				(clearance outline)
				(anchor circle)
			)
			(primitives
				(gr_poly
					(pts
						(arc
							(start 0.3048 -0.2032)
							(mid 0.275042 -0.275042)
							(end 0.2032 -0.3048)
						)
						(arc
							(start -0.2032 -0.3048)
							(mid -0.275042 -0.275042)
							(end -0.3048 -0.2032)
						)
						(arc
							(start -0.3048 0.2032)
							(mid -0.275042 0.275042)
							(end -0.2032 0.3048)
						)
						(arc
							(start 0.2032 0.3048)
							(mid 0.275042 0.275042)
							(end 0.3048 0.2032)
						)
					)
					(width 0)
					(fill yes)
				)
			)
		)
	)
	(footprint ""
		(layer "F.Cu")
		(at 45.338746 -145.3007 90)
		(property "Reference" "R212"
			(at 0 0 90)
			(layer "F.SilkS")
			(hide yes)
			(effects
				(font
					(size 1.27 1.27)
				)
			)
		)
		(property "Value" "10KR2F-2-GP"
			(at 0.064008 -3.993896 90)
			(unlocked yes)
			(layer "F.Fab")
			(hide yes)
			(effects
				(font
					(size 1.016 1.016)
					(thickness 0.1524)
				)
			)
		)
		(property "Device Type" "R402H16"
			(at 0.064008 -5.517896 90)
			(unlocked yes)
			(layer "F.Fab")
			(hide yes)
			(effects
				(font
					(size 1.016 1.016)
					(thickness 0.1524)
				)
			)
		)
		(duplicate_pad_numbers_are_jumpers no)
		(fp_line
			(start 0.508 -0.9398)
			(end -0.508 -0.9398)
			(stroke
				(width 0.1524)
				(type default)
			)
			(layer "F.SilkS")
		)
		(fp_line
			(start -0.508 -0.9398)
			(end -0.508 0.9398)
			(stroke
				(width 0.1524)
				(type default)
			)
			(layer "F.SilkS")
		)
		(fp_rect
			(start -0.508 0.9398)
			(end 0.508 -0.9398)
			(stroke
				(width 0)
				(type default)
			)
			(fill no)
			(layer "F.CrtYd")
		)
		(fp_rect
			(start -0.508 0.9398)
			(end 0.508 -0.9398)
			(stroke
				(width 0)
				(type default)
			)
			(fill no)
			(layer "F.Fab")
		)
		(pad "1" smd custom
			(at 0 -0.4445 90)
			(size 0.1397 0.1397)
			(layers "F.Cu" "F.Mask" "F.Paste")
			(net "P5VB")
			(options
				(clearance outline)
				(anchor circle)
			)
			(primitives
				(gr_poly
					(pts
						(arc
							(start -0.1778 -0.2794)
							(mid -0.249642 -0.249642)
							(end -0.2794 -0.1778)
						)
						(arc
							(start -0.2794 0.1778)
							(mid -0.249642 0.249642)
							(end -0.1778 0.2794)
						)
						(arc
							(start 0.1778 0.2794)
							(mid 0.249642 0.249642)
							(end 0.2794 0.1778)
						)
						(arc
							(start 0.2794 -0.1778)
							(mid 0.249642 -0.249642)
							(end 0.1778 -0.2794)
						)
					)
					(width 0)
					(fill yes)
				)
			)
		)
		(pad "2" smd custom
			(at 0 0.4445 90)
			(size 0.1397 0.1397)
			(layers "F.Cu" "F.Mask" "F.Paste")
			(net "DRIVE_ACT_8")
			(options
				(clearance outline)
				(anchor circle)
			)
			(primitives
				(gr_poly
					(pts
						(arc
							(start -0.1778 -0.2794)
							(mid -0.249642 -0.249642)
							(end -0.2794 -0.1778)
						)
						(arc
							(start -0.2794 0.1778)
							(mid -0.249642 0.249642)
							(end -0.1778 0.2794)
						)
						(arc
							(start 0.1778 0.2794)
							(mid 0.249642 0.249642)
							(end 0.2794 0.1778)
						)
						(arc
							(start 0.2794 -0.1778)
							(mid 0.249642 -0.249642)
							(end 0.1778 -0.2794)
						)
					)
					(width 0)
					(fill yes)
				)
			)
		)
	)
	(footprint ""
		(layer "F.Cu")
		(at 223.418654 -438.7723 90)
		(property "Reference" "PR52"
			(at 0 0 90)
			(layer "F.SilkS")
			(hide yes)
			(effects
				(font
					(size 1.27 1.27)
				)
			)
		)
		(property "Value" "2MR2F-GP"
			(at 0.064008 -3.993896 90)
			(unlocked yes)
			(layer "F.Fab")
			(hide yes)
			(effects
				(font
					(size 1.016 1.016)
					(thickness 0.1524)
				)
			)
		)
		(property "Device Type" "R402H16"
			(at 0.064008 -5.517896 90)
			(unlocked yes)
			(layer "F.Fab")
			(hide yes)
			(effects
				(font
					(size 1.016 1.016)
					(thickness 0.1524)
				)
			)
		)
		(duplicate_pad_numbers_are_jumpers no)
		(fp_line
			(start 0.508 -0.9398)
			(end -0.508 -0.9398)
			(stroke
				(width 0.1524)
				(type default)
			)
			(layer "F.SilkS")
		)
		(fp_line
			(start -0.508 -0.9398)
			(end -0.508 0.9398)
			(stroke
				(width 0.1524)
				(type default)
			)
			(layer "F.SilkS")
		)
		(fp_rect
			(start -0.508 0.9398)
			(end 0.508 -0.9398)
			(stroke
				(width 0)
				(type default)
			)
			(fill no)
			(layer "F.CrtYd")
		)
		(fp_rect
			(start -0.508 0.9398)
			(end 0.508 -0.9398)
			(stroke
				(width 0)
				(type default)
			)
			(fill no)
			(layer "F.Fab")
		)
		(pad "1" smd custom
			(at 0 -0.4445 90)
			(size 0.1397 0.1397)
			(layers "F.Cu" "F.Mask" "F.Paste")
			(net "P3V3_IN")
			(options
				(clearance outline)
				(anchor circle)
			)
			(primitives
				(gr_poly
					(pts
						(arc
							(start -0.1778 -0.2794)
							(mid -0.249642 -0.249642)
							(end -0.2794 -0.1778)
						)
						(arc
							(start -0.2794 0.1778)
							(mid -0.249642 0.249642)
							(end -0.1778 0.2794)
						)
						(arc
							(start 0.1778 0.2794)
							(mid 0.249642 0.249642)
							(end 0.2794 0.1778)
						)
						(arc
							(start 0.2794 -0.1778)
							(mid 0.249642 -0.249642)
							(end 0.1778 -0.2794)
						)
					)
					(width 0)
					(fill yes)
				)
			)
		)
		(pad "2" smd custom
			(at 0 0.4445 90)
			(size 0.1397 0.1397)
			(layers "F.Cu" "F.Mask" "F.Paste")
			(net "P3V3_EN")
			(options
				(clearance outline)
				(anchor circle)
			)
			(primitives
				(gr_poly
					(pts
						(arc
							(start -0.1778 -0.2794)
							(mid -0.249642 -0.249642)
							(end -0.2794 -0.1778)
						)
						(arc
							(start -0.2794 0.1778)
							(mid -0.249642 0.249642)
							(end -0.1778 0.2794)
						)
						(arc
							(start 0.1778 0.2794)
							(mid 0.249642 0.249642)
							(end 0.2794 0.1778)
						)
						(arc
							(start 0.2794 -0.1778)
							(mid 0.249642 -0.249642)
							(end 0.1778 -0.2794)
						)
					)
					(width 0)
					(fill yes)
				)
			)
		)
	)
	(footprint ""
		(layer "F.Cu")
		(at 34.543746 -107.470702 90)
		(property "Reference" "R472"
			(at 0 0 90)
			(layer "F.SilkS")
			(hide yes)
			(effects
				(font
					(size 1.27 1.27)
				)
			)
		)
		(property "Value" "4K7R2J-2-GP"
			(at 0.064008 -3.993896 90)
			(unlocked yes)
			(layer "F.Fab")
			(hide yes)
			(effects
				(font
					(size 1.016 1.016)
					(thickness 0.1524)
				)
			)
		)
		(property "Device Type" "R402H16"
			(at 0.064008 -5.517896 90)
			(unlocked yes)
			(layer "F.Fab")
			(hide yes)
			(effects
				(font
					(size 1.016 1.016)
					(thickness 0.1524)
				)
			)
		)
		(duplicate_pad_numbers_are_jumpers no)
		(fp_line
			(start 0.508 -0.9398)
			(end -0.508 -0.9398)
			(stroke
				(width 0.1524)
				(type default)
			)
			(layer "F.SilkS")
		)
		(fp_line
			(start -0.508 -0.9398)
			(end -0.508 0.9398)
			(stroke
				(width 0.1524)
				(type default)
			)
			(layer "F.SilkS")
		)
		(fp_rect
			(start -0.508 0.9398)
			(end 0.508 -0.9398)
			(stroke
				(width 0)
				(type default)
			)
			(fill no)
			(layer "F.CrtYd")
		)
		(fp_rect
			(start -0.508 0.9398)
			(end 0.508 -0.9398)
			(stroke
				(width 0)
				(type default)
			)
			(fill no)
			(layer "F.Fab")
		)
		(pad "1" smd custom
			(at 0 -0.4445 90)
			(size 0.1397 0.1397)
			(layers "F.Cu" "F.Mask" "F.Paste")
			(net "P3V3")
			(options
				(clearance outline)
				(anchor circle)
			)
			(primitives
				(gr_poly
					(pts
						(arc
							(start -0.1778 -0.2794)
							(mid -0.249642 -0.249642)
							(end -0.2794 -0.1778)
						)
						(arc
							(start -0.2794 0.1778)
							(mid -0.249642 0.249642)
							(end -0.1778 0.2794)
						)
						(arc
							(start 0.1778 0.2794)
							(mid 0.249642 0.249642)
							(end 0.2794 0.1778)
						)
						(arc
							(start 0.2794 -0.1778)
							(mid 0.249642 -0.249642)
							(end 0.1778 -0.2794)
						)
					)
					(width 0)
					(fill yes)
				)
			)
		)
		(pad "2" smd custom
			(at 0 0.4445 90)
			(size 0.1397 0.1397)
			(layers "F.Cu" "F.Mask" "F.Paste")
			(net "SAS_EXP_A_PWR13")
			(options
				(clearance outline)
				(anchor circle)
			)
			(primitives
				(gr_poly
					(pts
						(arc
							(start -0.1778 -0.2794)
							(mid -0.249642 -0.249642)
							(end -0.2794 -0.1778)
						)
						(arc
							(start -0.2794 0.1778)
							(mid -0.249642 0.249642)
							(end -0.1778 0.2794)
						)
						(arc
							(start 0.1778 0.2794)
							(mid 0.249642 0.249642)
							(end 0.2794 0.1778)
						)
						(arc
							(start 0.2794 -0.1778)
							(mid 0.249642 -0.249642)
							(end 0.1778 -0.2794)
						)
					)
					(width 0)
					(fill yes)
				)
			)
		)
	)
)
